(kicad_pcb
	(version 20240108)
	(generator "pcbnew")
	(generator_version "8.0")
	(general
		(thickness 1.62)
		(legacy_teardrops no)
	)
	(paper "A4")
	(title_block
		(title "Jetson Orin Baseboard")
		(date "2025-03-12")
		(rev "1.3.4")
		(company "Antmicro Ltd")
		(comment 1 "www.antmicro.com")
		(comment 9 "footprints 627-631 of 677")
	)
	(layers
		(0 "F.Cu" signal)
		(1 "In1.Cu" signal)
		(2 "In2.Cu" signal)
		(3 "In3.Cu" signal)
		(4 "In4.Cu" jumper)
		(5 "In5.Cu" signal)
		(6 "In6.Cu" signal)
		(31 "B.Cu" signal)
		(32 "B.Adhes" user "B.Adhesive")
		(33 "F.Adhes" user "F.Adhesive")
		(34 "B.Paste" user)
		(35 "F.Paste" user)
		(36 "B.SilkS" user "B.Silkscreen")
		(37 "F.SilkS" user "F.Silkscreen")
		(38 "B.Mask" user)
		(39 "F.Mask" user)
		(40 "Dwgs.User" user "User.Drawings")
		(41 "Cmts.User" user "User.Comments")
		(42 "Eco1.User" user "User.Eco1")
		(43 "Eco2.User" user "User.Eco2")
		(44 "Edge.Cuts" user)
		(45 "Margin" user)
		(46 "B.CrtYd" user "B.Courtyard")
		(47 "F.CrtYd" user "F.Courtyard")
		(48 "B.Fab" user)
		(49 "F.Fab" user)
	)
	(footprint "antmicro-footprints:WSON-6-1EP_2x2mm_P0.65mm"
		(layer "B.Cu")
		(at 73.8 80.1)
		(property "Reference" "U41"
			(at 1.02 2.02 180)
			(layer "B.SilkS")
			(effects
				(font
					(size 0.7 0.7)
					(thickness 0.15)
				)
				(justify left bottom mirror)
			)
		)
		(property "Value" "NCP730BMT330_WSON"
			(at 0 -2.2 180)
			(layer "B.Fab")
			(effects
				(font
					(size 0.7 0.7)
					(thickness 0.15)
				)
				(justify left bottom mirror)
			)
		)
		(property "Footprint" "antmicro-footprints:WSON-6-1EP_2x2mm_P0.65mm"
			(at 0 0 0)
			(layer "F.Fab")
			(hide yes)
			(effects
				(font
					(size 1.27 1.27)
					(thickness 0.15)
				)
			)
		)
		(property "Datasheet" "https://www.onsemi.com/download/data-sheet/pdf/ncp730-d.pdf"
			(at 0 0 0)
			(layer "F.Fab")
			(hide yes)
			(effects
				(font
					(size 1.27 1.27)
					(thickness 0.15)
				)
			)
		)
		(property "Author" "Antmicro"
			(at 0 0 0)
			(layer "B.Fab")
			(hide yes)
			(effects
				(font
					(size 1 1)
					(thickness 0.15)
				)
				(justify mirror)
			)
		)
		(property "License" "Apache-2.0"
			(at 0 0 0)
			(layer "B.Fab")
			(hide yes)
			(effects
				(font
					(size 1 1)
					(thickness 0.15)
				)
				(justify mirror)
			)
		)
		(property "MPN" "NCP730BMT330TBG"
			(at 0 0 0)
			(layer "B.Fab")
			(hide yes)
			(effects
				(font
					(size 1 1)
					(thickness 0.15)
				)
				(justify mirror)
			)
		)
		(property "Manufacturer" "ON Semiconductor"
			(at 0 0 0)
			(layer "B.Fab")
			(hide yes)
			(effects
				(font
					(size 1 1)
					(thickness 0.15)
				)
				(justify mirror)
			)
		)
		(sheetname "Supply")
		(sheetfile "supply.kicad_sch")
		(attr smd)
		(fp_line
			(start -1.05 1)
			(end 1 1)
			(stroke
				(width 0.12)
				(type solid)
			)
			(layer "B.SilkS")
		)
		(fp_line
			(start 1 -1)
			(end -1 -1)
			(stroke
				(width 0.12)
				(type solid)
			)
			(layer "B.SilkS")
		)
		(fp_circle
			(center -1.275 1.075)
			(end -1.224 1.075)
			(stroke
				(width 0.15)
				(type solid)
			)
			(fill solid)
			(layer "B.SilkS")
		)
		(fp_rect
			(start -1.45 1.25)
			(end 1.45 -1.25)
			(stroke
				(width 0.05)
				(type solid)
			)
			(fill none)
			(layer "B.CrtYd")
		)
		(fp_text user "License: Apache-2.0"
			(at -1.01 -6.4 180)
			(layer "B.Fab")
			(hide yes)
			(effects
				(font
					(size 0.7 0.7)
					(thickness 0.15)
				)
				(justify left bottom mirror)
			)
		)
		(fp_text user "Author: Antmicro"
			(at -1.01 -5.2 180)
			(layer "B.Fab")
			(hide yes)
			(effects
				(font
					(size 0.7 0.7)
					(thickness 0.15)
				)
				(justify left bottom mirror)
			)
		)
		(fp_text user "${REFERENCE}"
			(at -1.01 -3.999 180)
			(layer "B.Fab")
			(hide yes)
			(effects
				(font
					(size 0.7 0.7)
					(thickness 0.15)
				)
				(justify left bottom mirror)
			)
		)
		(pad "1" smd roundrect
			(at -0.975 0.652)
			(size 0.45 0.4)
			(layers "B.Cu" "B.Paste" "B.Mask")
			(roundrect_rratio 0.25)
			(net 138 "/Supply/3V3_LDO")
			(pinfunction "V_{OUT}")
			(pintype "power_out")
		)
		(pad "2" smd roundrect
			(at -0.975 0)
			(size 0.45 0.4)
			(layers "B.Cu" "B.Paste" "B.Mask")
			(roundrect_rratio 0.25)
			(net 725 "unconnected-(U41-NC-Pad2)")
			(pinfunction "NC")
			(pintype "no_connect")
		)
		(pad "3" smd roundrect
			(at -0.975 -0.65)
			(size 0.45 0.4)
			(layers "B.Cu" "B.Paste" "B.Mask")
			(roundrect_rratio 0.25)
			(net 1 "GND")
			(pinfunction "GND")
			(pintype "power_in")
		)
		(pad "4" smd roundrect
			(at 0.973 -0.65)
			(size 0.45 0.4)
			(layers "B.Cu" "B.Paste" "B.Mask")
			(roundrect_rratio 0.25)
			(net 115 "VCC")
			(pinfunction "EN")
			(pintype "input")
		)
		(pad "5" smd roundrect
			(at 0.973 0)
			(size 0.45 0.4)
			(layers "B.Cu" "B.Paste" "B.Mask")
			(roundrect_rratio 0.25)
			(net 1 "GND")
			(pinfunction "PG")
			(pintype "open_collector")
		)
		(pad "6" smd roundrect
			(at 0.973 0.652)
			(size 0.45 0.4)
			(layers "B.Cu" "B.Paste" "B.Mask")
			(roundrect_rratio 0.25)
			(net 115 "VCC")
			(pinfunction "V_{IN}")
			(pintype "power_in")
		)
		(pad "7" smd roundrect
			(at 0 0)
			(size 1.12 1.72)
			(layers "B.Cu" "B.Paste" "B.Mask")
			(roundrect_rratio 0.1)
			(net 1 "GND")
			(pinfunction "GND")
			(pintype "passive")
		)
	)
	(footprint "antmicro-footprints:R_Array_4x0201_Panasonic_EXB18V"
		(layer "B.Cu")
		(at 91.6 112.25 180)
		(property "Reference" "R195"
			(at 0.25 0.75 0)
			(layer "B.SilkS")
			(effects
				(font
					(size 0.7 0.7)
					(thickness 0.15)
				)
				(justify right bottom mirror)
			)
		)
		(property "Value" "R_4x0R_0201_array"
			(at -1.1 -1.8 0)
			(layer "B.Fab")
			(effects
				(font
					(size 0.7 0.7)
					(thickness 0.15)
				)
				(justify left bottom mirror)
			)
		)
		(property "Footprint" "antmicro-footprints:R_Array_4x0201_Panasonic_EXB18V"
			(at 0 0 180)
			(layer "F.Fab")
			(hide yes)
			(effects
				(font
					(size 1.27 1.27)
					(thickness 0.15)
				)
			)
		)
		(property "Datasheet" "http://industrial.panasonic.com/cdbs/www-data/pdf/AOC0000/AOC0000C14.pdf"
			(at 0 0 180)
			(layer "F.Fab")
			(hide yes)
			(effects
				(font
					(size 1.27 1.27)
					(thickness 0.15)
				)
			)
		)
		(property "Author" "Antmicro"
			(at 183.2 224.5 0)
			(layer "B.Fab")
			(hide yes)
			(effects
				(font
					(size 1 1)
					(thickness 0.15)
				)
				(justify mirror)
			)
		)
		(property "License" "Apache-2.0"
			(at 183.2 224.5 0)
			(layer "B.Fab")
			(hide yes)
			(effects
				(font
					(size 1 1)
					(thickness 0.15)
				)
				(justify mirror)
			)
		)
		(property "MPN" "EXB-18VR000X"
			(at 183.2 224.5 0)
			(layer "B.Fab")
			(hide yes)
			(effects
				(font
					(size 1 1)
					(thickness 0.15)
				)
				(justify mirror)
			)
		)
		(property "Manufacturer" "Panasonic"
			(at 183.2 224.5 0)
			(layer "B.Fab")
			(hide yes)
			(effects
				(font
					(size 1 1)
					(thickness 0.15)
				)
				(justify mirror)
			)
		)
		(property "Val" "4x0R_0201"
			(at 183.2 224.5 0)
			(layer "B.Fab")
			(hide yes)
			(effects
				(font
					(size 1 1)
					(thickness 0.15)
				)
				(justify mirror)
			)
		)
		(sheetname "Peripherals")
		(sheetfile "peripherals.kicad_sch")
		(attr smd)
		(fp_line
			(start 0.8 -0.45)
			(end 0.8 0.45)
			(stroke
				(width 0.12)
				(type solid)
			)
			(layer "B.SilkS")
		)
		(fp_line
			(start -0.8 -0.45)
			(end -0.8 0.45)
			(stroke
				(width 0.12)
				(type solid)
			)
			(layer "B.SilkS")
		)
		(fp_rect
			(start -0.898 0.66)
			(end 0.898 -0.65)
			(stroke
				(width 0.05)
				(type solid)
			)
			(fill none)
			(layer "B.CrtYd")
		)
		(fp_text user "Author: Antmicro"
			(at -1.051 -4.599 0)
			(layer "B.Fab")
			(hide yes)
			(effects
				(font
					(size 0.7 0.7)
					(thickness 0.15)
				)
				(justify left bottom mirror)
			)
		)
		(fp_text user "License: Apache-2.0"
			(at -1.051 -6 0)
			(layer "B.Fab")
			(hide yes)
			(effects
				(font
					(size 0.7 0.7)
					(thickness 0.15)
				)
				(justify left bottom mirror)
			)
		)
		(fp_text user "${REFERENCE}"
			(at -1.051 -3.2 0)
			(layer "B.Fab")
			(hide yes)
			(effects
				(font
					(size 0.7 0.7)
					(thickness 0.15)
				)
				(justify left bottom mirror)
			)
		)
		(pad "1" smd roundrect
			(at -0.6 -0.298 180)
			(size 0.2 0.4)
			(layers "B.Cu" "B.Paste" "B.Mask")
			(roundrect_rratio 0.25)
			(net 311 "CSIA_FLG")
			(pinfunction "R1.1")
			(pintype "passive")
		)
		(pad "2" smd roundrect
			(at -0.202 -0.298 180)
			(size 0.2 0.4)
			(layers "B.Cu" "B.Paste" "B.Mask")
			(roundrect_rratio 0.25)
			(net 393 "CSIB_FLG")
			(pinfunction "R2.1")
			(pintype "passive")
		)
		(pad "3" smd roundrect
			(at 0.2 -0.298 180)
			(size 0.2 0.4)
			(layers "B.Cu" "B.Paste" "B.Mask")
			(roundrect_rratio 0.25)
			(net 508 "USBC1_FLG")
			(pinfunction "R3.1")
			(pintype "passive")
		)
		(pad "4" smd roundrect
			(at 0.598 -0.298 180)
			(size 0.2 0.4)
			(layers "B.Cu" "B.Paste" "B.Mask")
			(roundrect_rratio 0.25)
			(net 505 "USBC0_FLG")
			(pinfunction "R4.1")
			(pintype "passive")
		)
		(pad "5" smd roundrect
			(at 0.598 0.3 180)
			(size 0.2 0.4)
			(layers "B.Cu" "B.Paste" "B.Mask")
			(roundrect_rratio 0.25)
			(net 545 "/Peripherals/GPIOEX_P0_7")
			(pinfunction "R4.2")
			(pintype "passive")
		)
		(pad "6" smd roundrect
			(at 0.2 0.3 180)
			(size 0.2 0.4)
			(layers "B.Cu" "B.Paste" "B.Mask")
			(roundrect_rratio 0.25)
			(net 546 "/Peripherals/GPIOEX_P0_6")
			(pinfunction "R3.2")
			(pintype "passive")
		)
		(pad "7" smd roundrect
			(at -0.202 0.3 180)
			(size 0.2 0.4)
			(layers "B.Cu" "B.Paste" "B.Mask")
			(roundrect_rratio 0.25)
			(net 604 "/Peripherals/GPIOEX_P0_5")
			(pinfunction "R2.2")
			(pintype "passive")
		)
		(pad "8" smd roundrect
			(at -0.6 0.3 180)
			(size 0.2 0.4)
			(layers "B.Cu" "B.Paste" "B.Mask")
			(roundrect_rratio 0.25)
			(net 605 "/Peripherals/GPIOEX_P0_4")
			(pinfunction "R1.2")
			(pintype "passive")
		)
	)
	(footprint "antmicro-footprints:R_0402_1005Metric"
		(layer "B.Cu")
		(at 45.15 119.925)
		(descr "Resistor SMD 0402")
		(tags "resistor SMD 0402")
		(property "Reference" "R271"
			(at -1.71 1.015 90)
			(layer "B.SilkS")
			(effects
				(font
					(size 0.7 0.7)
					(thickness 0.15)
				)
				(justify right bottom mirror)
			)
		)
		(property "Value" "R_10M_0402"
			(at -1.011843 -1.772047 0)
			(layer "B.Fab")
			(effects
				(font
					(size 0.7 0.7)
					(thickness 0.15)
				)
				(justify right bottom mirror)
			)
		)
		(property "Footprint" "antmicro-footprints:R_0402_1005Metric"
			(at 0 0 0)
			(layer "F.Fab")
			(hide yes)
			(effects
				(font
					(size 1.27 1.27)
					(thickness 0.15)
				)
			)
		)
		(property "Datasheet" "https://www.bourns.com/docs/product-datasheets/cr.pdf"
			(at 0 0 0)
			(layer "F.Fab")
			(hide yes)
			(effects
				(font
					(size 1.27 1.27)
					(thickness 0.15)
				)
			)
		)
		(property "Author" "Antmicro"
			(at 0 0 0)
			(layer "B.Fab")
			(hide yes)
			(effects
				(font
					(size 1 1)
					(thickness 0.15)
				)
				(justify mirror)
			)
		)
		(property "License" "Apache-2.0"
			(at 0 0 0)
			(layer "B.Fab")
			(hide yes)
			(effects
				(font
					(size 1 1)
					(thickness 0.15)
				)
				(justify mirror)
			)
		)
		(property "MPN" "CR0402-FX-1005GLF"
			(at 0 0 0)
			(layer "B.Fab")
			(hide yes)
			(effects
				(font
					(size 1 1)
					(thickness 0.15)
				)
				(justify mirror)
			)
		)
		(property "Manufacturer" "Bourns"
			(at 0 0 0)
			(layer "B.Fab")
			(hide yes)
			(effects
				(font
					(size 1 1)
					(thickness 0.15)
				)
				(justify mirror)
			)
		)
		(property "Tolerance" "1%"
			(at 0 0 0)
			(layer "B.Fab")
			(hide yes)
			(effects
				(font
					(size 1 1)
					(thickness 0.15)
				)
				(justify mirror)
			)
		)
		(property "Val" "10M"
			(at 0 0 0)
			(layer "B.Fab")
			(hide yes)
			(effects
				(font
					(size 1 1)
					(thickness 0.15)
				)
				(justify mirror)
			)
		)
		(sheetname "USB Debug, DP")
		(sheetfile "usb.kicad_sch")
		(attr smd exclude_from_pos_files exclude_from_bom dnp)
		(fp_rect
			(start -0.925 0.47)
			(end 0.925 -0.47)
			(stroke
				(width 0.05)
				(type default)
			)
			(fill none)
			(layer "B.CrtYd")
		)
		(fp_rect
			(start -0.5 0.25)
			(end 0.5 -0.25)
			(stroke
				(width 0.15)
				(type solid)
			)
			(fill none)
			(layer "B.Fab")
		)
		(fp_text user "${REFERENCE}"
			(at -0.95 -3.168 0)
			(layer "B.Fab")
			(hide yes)
			(effects
				(font
					(size 0.7 0.7)
					(thickness 0.15)
				)
				(justify right bottom mirror)
			)
		)
		(fp_text user "License: Apache-2.0"
			(at -0.95 -5.169 0)
			(layer "B.Fab")
			(hide yes)
			(effects
				(font
					(size 0.7 0.7)
					(thickness 0.15)
				)
				(justify right bottom mirror)
			)
		)
		(fp_text user "Author: Antmicro"
			(at -0.95 -4.169 0)
			(layer "B.Fab")
			(hide yes)
			(effects
				(font
					(size 0.7 0.7)
					(thickness 0.15)
				)
				(justify right bottom mirror)
			)
		)
		(pad "1" smd roundrect
			(at -0.48 0)
			(size 0.59 0.64)
			(layers "B.Cu" "B.Paste" "B.Mask")
			(roundrect_rratio 0.25)
			(net 1 "GND")
			(pintype "passive")
		)
		(pad "2" smd roundrect
			(at 0.48 0)
			(size 0.59 0.64)
			(layers "B.Cu" "B.Paste" "B.Mask")
			(roundrect_rratio 0.25)
			(net 86 "~{RESET}")
			(pintype "passive")
		)
	)
	(footprint "antmicro-footprints:Fiducial_1mm_Mask2mm"
		(layer "B.Cu")
		(at 31.25 127.25 180)
		(descr "Circular Fiducial, 1mm bare copper, 3mm soldermask opening")
		(tags "fiducial")
		(property "Reference" "FID5"
			(at 0 1.4 0)
			(layer "B.SilkS")
			(hide yes)
			(effects
				(font
					(size 0.7 0.7)
					(thickness 0.15)
				)
				(justify left bottom mirror)
			)
		)
		(property "Value" "Fiducial_1mm_Mask2mm"
			(at 0 -2.2 0)
			(layer "B.Fab")
			(effects
				(font
					(size 0.7 0.7)
					(thickness 0.15)
				)
				(justify left bottom mirror)
			)
		)
		(property "Footprint" "antmicro-footprints:Fiducial_1mm_Mask2mm"
			(at 0 0 180)
			(layer "F.Fab")
			(hide yes)
			(effects
				(font
					(size 1.27 1.27)
					(thickness 0.15)
				)
			)
		)
		(attr board_only exclude_from_pos_files exclude_from_bom)
		(fp_circle
			(center 0 0)
			(end 1.24 0)
			(stroke
				(width 0.05)
				(type solid)
			)
			(fill none)
			(layer "B.CrtYd")
		)
		(fp_circle
			(center 0 0)
			(end 0.999 0)
			(stroke
				(width 0.15)
				(type solid)
			)
			(fill none)
			(layer "B.Fab")
		)
		(fp_text user "${REFERENCE}"
			(at -1.25 -4.603 0)
			(layer "B.Fab")
			(hide yes)
			(effects
				(font
					(size 0.7 0.7)
					(thickness 0.15)
				)
				(justify left bottom mirror)
			)
		)
		(fp_text user "Author: Antmicro"
			(at -1.25 -5.803 0)
			(layer "B.Fab")
			(hide yes)
			(effects
				(font
					(size 0.7 0.7)
					(thickness 0.15)
				)
				(justify left bottom mirror)
			)
		)
		(fp_text user "License: Apache-2.0"
			(at -1.25 -7.003 0)
			(layer "B.Fab")
			(hide yes)
			(effects
				(font
					(size 0.7 0.7)
					(thickness 0.15)
				)
				(justify left bottom mirror)
			)
		)
		(pad "" smd circle
			(at 0 0 180)
			(size 1 1)
			(layers "B.Cu" "B.Mask")
			(solder_mask_margin 0.5)
			(clearance 0.5)
		)
	)
	(footprint "antmicro-footprints:C_0402_1005Metric"
		(layer "B.Cu")
		(at 49.75 113.75 180)
		(descr "Capacitor SMD 0402")
		(tags "capacitor SMD 0402")
		(property "Reference" "C27"
			(at 13.12 -9.78 0)
			(layer "B.SilkS")
			(effects
				(font
					(size 0.7 0.7)
					(thickness 0.15)
				)
				(justify left bottom mirror)
			)
		)
		(property "Value" "C_100n_0402"
			(at 0 -1.4 0)
			(layer "B.Fab")
			(effects
				(font
					(size 0.7 0.7)
					(thickness 0.15)
				)
				(justify left bottom mirror)
			)
		)
		(property "Footprint" "antmicro-footprints:C_0402_1005Metric"
			(at 0 0 180)
			(layer "F.Fab")
			(hide yes)
			(effects
				(font
					(size 1.27 1.27)
					(thickness 0.15)
				)
			)
		)
		(property "Datasheet" "https://www.murata.com/products/productdetail?partno=GRM155R61H104KE14%23"
			(at 0 0 180)
			(layer "F.Fab")
			(hide yes)
			(effects
				(font
					(size 1.27 1.27)
					(thickness 0.15)
				)
			)
		)
		(property "Author" "Antmicro"
			(at 99.5 227.5 0)
			(layer "B.Fab")
			(hide yes)
			(effects
				(font
					(size 1 1)
					(thickness 0.15)
				)
				(justify mirror)
			)
		)
		(property "Dielectric" "X5R"
			(at 99.5 227.5 0)
			(layer "B.Fab")
			(hide yes)
			(effects
				(font
					(size 1 1)
					(thickness 0.15)
				)
				(justify mirror)
			)
		)
		(property "License" "Apache-2.0"
			(at 99.5 227.5 0)
			(layer "B.Fab")
			(hide yes)
			(effects
				(font
					(size 1 1)
					(thickness 0.15)
				)
				(justify mirror)
			)
		)
		(property "MPN" "GRM155R61H104KE14D"
			(at 99.5 227.5 0)
			(layer "B.Fab")
			(hide yes)
			(effects
				(font
					(size 1 1)
					(thickness 0.15)
				)
				(justify mirror)
			)
		)
		(property "Manufacturer" "Murata"
			(at 99.5 227.5 0)
			(layer "B.Fab")
			(hide yes)
			(effects
				(font
					(size 1 1)
					(thickness 0.15)
				)
				(justify mirror)
			)
		)
		(property "Val" "100n"
			(at 99.5 227.5 0)
			(layer "B.Fab")
			(hide yes)
			(effects
				(font
					(size 1 1)
					(thickness 0.15)
				)
				(justify mirror)
			)
		)
		(property "Voltage" "50V"
			(at 99.5 227.5 0)
			(layer "B.Fab")
			(hide yes)
			(effects
				(font
					(size 1 1)
					(thickness 0.15)
				)
				(justify mirror)
			)
		)
		(sheetname "USB Debug, DP")
		(sheetfile "usb.kicad_sch")
		(attr smd)
		(fp_rect
			(start -0.925 0.47)
			(end 0.925 -0.47)
			(stroke
				(width 0.05)
				(type default)
			)
			(fill none)
			(layer "B.CrtYd")
		)
		(fp_line
			(start 0.504 0.25)
			(end -0.494 0.25)
			(stroke
				(width 0.15)
				(type solid)
			)
			(layer "B.Fab")
		)
		(fp_line
			(start 0.504 -0.248)
			(end 0.504 0.25)
			(stroke
				(width 0.15)
				(type solid)
			)
			(layer "B.Fab")
		)
		(fp_line
			(start -0.494 0.25)
			(end -0.494 -0.248)
			(stroke
				(width 0.15)
				(type solid)
			)
			(layer "B.Fab")
		)
		(fp_line
			(start -0.494 -0.248)
			(end 0.504 -0.248)
			(stroke
				(width 0.15)
				(type solid)
			)
			(layer "B.Fab")
		)
		(fp_text user "${REFERENCE}"
			(at -0.932 -3.168 0)
			(layer "B.Fab")
			(hide yes)
			(effects
				(font
					(size 0.7 0.7)
					(thickness 0.15)
				)
				(justify left bottom mirror)
			)
		)
		(fp_text user "Author: Antmicro"
			(at -0.932 -4.17 0)
			(layer "B.Fab")
			(hide yes)
			(effects
				(font
					(size 0.7 0.7)
					(thickness 0.15)
				)
				(justify left bottom mirror)
			)
		)
		(fp_text user "License: Apache-2.0"
			(at -0.932 -5.17 0)
			(layer "B.Fab")
			(hide yes)
			(effects
				(font
					(size 0.7 0.7)
					(thickness 0.15)
				)
				(justify left bottom mirror)
			)
		)
		(pad "1" smd roundrect
			(at -0.48 0 180)
			(size 0.59 0.64)
			(layers "B.Cu" "B.Paste" "B.Mask")
			(roundrect_rratio 0.25)
			(net 185 "/USB Debug, DP/FTDI_3V3")
			(pintype "passive")
		)
		(pad "2" smd roundrect
			(at 0.48 0 180)
			(size 0.59 0.64)
			(layers "B.Cu" "B.Paste" "B.Mask")
			(roundrect_rratio 0.25)
			(net 1 "GND")
			(pintype "passive")
		)
	)
)
